#ISCELL
  mstr_misc dns *
  *
#ISCELL
  pure_quanta quanta_title_block_c *
  *
#ISCELL
  pure_quanta_power design_note *
  *
#ISCELL
  standard offpage *
  page348_i1
#ISCELL
  standard offpage *
  page348_i10
#CELL
  pure_quanta q_res *
  page348_i101
#CELL
  pure_quanta q_res *
  page348_i102
#CELL
  pure_quanta q_res *
  page348_i103
#CELL
  pure_quanta q_res *
  page348_i104
#CELL
  pure_quanta q_res *
  page348_i105
#ISCELL
  standard offpage *
  page348_i106
#ISCELL
  standard offpage *
  page348_i107
#ISCELL
  standard offpage *
  page348_i108
#ISCELL
  standard offpage *
  page348_i109
#ISCELL
  standard offpage *
  page348_i11
#ISCELL
  standard offpage *
  page348_i110
#ISCELL
  standard offpage *
  page348_i111
#ISCELL
  standard offpage *
  page348_i112
#ISCELL
  standard offpage *
  page348_i113
#ISCELL
  standard offpage *
  page348_i114
#ISCELL
  standard offpage *
  page348_i115
#ISCELL
  standard offpage *
  page348_i116
#CELL
  pure_quanta q_res *
  page348_i117
#CELL
  pure_quanta q_res *
  page348_i118
#CELL
  pure_quanta q_res *
  page348_i119
#ISCELL
  standard offpage *
  page348_i12
#CELL
  pure_quanta q_res *
  page348_i120
#CELL
  pure_quanta q_res *
  page348_i121
#CELL
  pure_quanta q_res *
  page348_i122
#CELL
  pure_quanta q_res *
  page348_i123
#CELL
  pure_quanta q_res *
  page348_i124
#ISCELL
  standard offpage *
  page348_i125
#ISCELL
  pure_quanta_power universal_power *
  page348_i126
#ISCELL
  pure_quanta_power universal_power *
  page348_i127
#CELL
  pure_quanta q_res *
  page348_i128
#CELL
  pure_quanta q_res *
  page348_i129
#CELL
  pure_quanta q_res *
  page348_i130
#CELL
  pure_quanta q_res *
  page348_i131
#CELL
  pure_quanta q_res *
  page348_i132
#CELL
  pure_quanta q_res *
  page348_i133
#CELL
  pure_quanta q_res *
  page348_i134
#CELL
  pure_quanta q_res *
  page348_i135
#ISCELL
  standard offpage *
  page348_i136
#ISCELL
  standard offpage *
  page348_i137
#ISCELL
  standard offpage *
  page348_i138
#ISCELL
  standard offpage *
  page348_i139
#ISCELL
  standard offpage *
  page348_i14
#ISCELL
  standard offpage *
  page348_i140
#ISCELL
  standard offpage *
  page348_i141
#ISCELL
  standard offpage *
  page348_i142
#ISCELL
  standard offpage *
  page348_i143
#ISCELL
  standard offpage *
  page348_i144
#ISCELL
  standard offpage *
  page348_i145
#ISCELL
  standard offpage *
  page348_i146
#ISCELL
  standard offpage *
  page348_i147
#ISCELL
  standard offpage *
  page348_i148
#ISCELL
  standard offpage *
  page348_i149
#ISCELL
  standard offpage *
  page348_i150
#ISCELL
  standard offpage *
  page348_i151
#ISCELL
  standard offpage *
  page348_i152
#ISCELL
  standard offpage *
  page348_i153
#ISCELL
  standard offpage *
  page348_i154
#ISCELL
  standard offpage *
  page348_i155
#ISCELL
  standard offpage *
  page348_i156
#ISCELL
  standard offpage *
  page348_i157
#ISCELL
  standard offpage *
  page348_i158
#ISCELL
  standard offpage *
  page348_i159
#ISCELL
  pure_quanta_power universal_gnd *
  page348_i16
#ISCELL
  standard offpage *
  page348_i160
#ISCELL
  standard offpage *
  page348_i161
#ISCELL
  standard offpage *
  page348_i162
#ISCELL
  standard offpage *
  page348_i163
#ISCELL
  standard offpage *
  page348_i164
#ISCELL
  standard offpage *
  page348_i166
#ISCELL
  standard offpage *
  page348_i167
#ISCELL
  standard offpage *
  page348_i168
#CELL
  pure_quanta q_res *
  page348_i169
#CELL
  pure_quanta q_res *
  page348_i17
#ISCELL
  pure_quanta_power universal_gnd *
  page348_i170
#CELL
  pure_quanta q_res *
  page348_i171
#ISCELL
  pure_quanta_power vcc_core *
  page348_i172
#ISCELL
  pure_quanta_power universal_gnd *
  page348_i173
#CELL
  pure_quanta q_res *
  page348_i174
#ISCELL
  standard offpage *
  page348_i175
#CELL
  pure_quanta sconn168_me1016810202011 *
  page348_i176
#CELL
  pure_quanta q_res *
  page348_i177
#CELL
  pure_quanta q_res *
  page348_i178
#ISCELL
  standard offpage *
  page348_i179
#CELL
  pure_quanta q_res *
  page348_i18
#ISCELL
  standard offpage *
  page348_i180
#ISCELL
  pure_quanta_power vcc_core *
  page348_i182
#ISCELL
  standard offpage *
  page348_i185
#ISCELL
  pure_quanta_power universal_power *
  page348_i19
#CELL
  pure_quanta q_res *
  page348_i190
#CELL
  pure_quanta q_res *
  page348_i191
#ISCELL
  standard offpage *
  page348_i192
#CELL
  pure_quanta q_res *
  page348_i195
#CELL
  pure_quanta q_res *
  page348_i196
#ISCELL
  standard offpage *
  page348_i197
#ISCELL
  standard offpage *
  page348_i198
#ISCELL
  standard offpage *
  page348_i199
#ISCELL
  standard offpage *
  page348_i2
#ISCELL
  standard offpage *
  page348_i20
#ISCELL
  standard offpage *
  page348_i200
#ISCELL
  standard offpage *
  page348_i201
#ISCELL
  standard offpage *
  page348_i202
#ISCELL
  standard offpage *
  page348_i203
#ISCELL
  standard offpage *
  page348_i204
#ISCELL
  standard offpage *
  page348_i205
#ISCELL
  standard offpage *
  page348_i206
#ISCELL
  standard offpage *
  page348_i207
#ISCELL
  standard offpage *
  page348_i208
#ISCELL
  standard offpage *
  page348_i209
#ISCELL
  standard offpage *
  page348_i21
#ISCELL
  standard offpage *
  page348_i210
#ISCELL
  standard offpage *
  page348_i211
#ISCELL
  standard offpage *
  page348_i212
#ISCELL
  standard offpage *
  page348_i213
#CELL
  pure_quanta q_res *
  page348_i214
#CELL
  pure_quanta q_res *
  page348_i215
#ISCELL
  standard offpage *
  page348_i216
#ISCELL
  standard offpage *
  page348_i217
#CELL
  pure_quanta q_cap *
  page348_i219
#ISCELL
  standard offpage *
  page348_i22
#CELL
  pure_quanta q_res *
  page348_i220
#ISCELL
  pure_quanta_power universal_gnd *
  page348_i221
#ISCELL
  standard offpage *
  page348_i23
#CELL
  pure_quanta q_res *
  page348_i24
#CELL
  pure_quanta q_res *
  page348_i25
#CELL
  pure_quanta q_res *
  page348_i26
#CELL
  pure_quanta q_res *
  page348_i27
#CELL
  pure_quanta q_res *
  page348_i28
#CELL
  pure_quanta q_res *
  page348_i29
#ISCELL
  standard offpage *
  page348_i3
#CELL
  pure_quanta q_res *
  page348_i30
#CELL
  pure_quanta q_res *
  page348_i31
#CELL
  pure_quanta q_res *
  page348_i32
#CELL
  pure_quanta q_res *
  page348_i33
#CELL
  pure_quanta q_res *
  page348_i34
#CELL
  pure_quanta q_res *
  page348_i35
#ISCELL
  standard offpage *
  page348_i36
#ISCELL
  standard offpage *
  page348_i37
#ISCELL
  standard offpage *
  page348_i38
#ISCELL
  standard offpage *
  page348_i39
#ISCELL
  standard offpage *
  page348_i4
#ISCELL
  pure_quanta_power universal_gnd *
  page348_i40
#ISCELL
  pure_quanta_power universal_gnd *
  page348_i41
#CELL
  pure_quanta q_res *
  page348_i42
#CELL
  pure_quanta q_res *
  page348_i43
#ISCELL
  standard offpage *
  page348_i46
#ISCELL
  standard offpage *
  page348_i47
#ISCELL
  standard offpage *
  page348_i48
#ISCELL
  standard offpage *
  page348_i49
#ISCELL
  standard offpage *
  page348_i5
#CELL
  pure_quanta q_res *
  page348_i50
#ISCELL
  standard offpage *
  page348_i51
#ISCELL
  standard offpage *
  page348_i52
#ISCELL
  standard offpage *
  page348_i53
#ISCELL
  standard offpage *
  page348_i54
#ISCELL
  standard offpage *
  page348_i55
#ISCELL
  standard offpage *
  page348_i56
#ISCELL
  standard offpage *
  page348_i57
#ISCELL
  pure_quanta_power universal_gnd *
  page348_i58
#ISCELL
  standard offpage *
  page348_i6
#CELL
  pure_quanta q_res *
  page348_i60
#ISCELL
  standard offpage *
  page348_i62
#ISCELL
  standard offpage *
  page348_i63
#ISCELL
  standard offpage *
  page348_i67
#ISCELL
  standard offpage *
  page348_i68
#ISCELL
  standard offpage *
  page348_i7
#ISCELL
  standard offpage *
  page348_i72
#ISCELL
  standard offpage *
  page348_i73
#ISCELL
  standard offpage *
  page348_i75
#ISCELL
  standard offpage *
  page348_i77
#ISCELL
  standard offpage *
  page348_i78
#ISCELL
  standard offpage *
  page348_i8
#ISCELL
  standard offpage *
  page348_i80
#ISCELL
  standard offpage *
  page348_i83
#CELL
  pure_quanta q_res *
  page348_i85
#CELL
  pure_quanta q_res *
  page348_i86
#CELL
  pure_quanta q_res *
  page348_i87
#CELL
  pure_quanta q_res *
  page348_i88
#ISCELL
  standard offpage *
  page348_i9
#ISCELL
  standard offpage *
  page348_i91
#ISCELL
  standard offpage *
  page348_i92
#ISCELL
  standard offpage *
  page348_i93
#ISCELL
  standard offpage *
  page348_i94
#ISCELL
  standard offpage *
  page348_i95
#CELL
  pure_quanta q_res *
  page348_i96
#CELL
  pure_quanta q_res *
  page348_i97
#CELL
  pure_quanta q_res *
  page348_i98
